# T6G (Grand Teton) — schematic netlist excerpt (pin names and nets, part order shuffled) for the footprints in the layout excerpt that follows; sources: Cadence DE-HDL packaged netlist, KiCad conversion of 04192023_DAF0TMB3IC0_F0TG_MB_C_brd_V02_OCP.brd

PR275  Q_RES  8.87K 1% EMPTY  pkg 0402LF  page 222 : A = PVDDIO_P1_LSET1 ; B = GND
R3489  Q_RES  100K 1% EMPTY  pkg 0402LF  page 129 : A = GPU_FPGA_EROT_RST_N ; B = GND
C901  Q_CAP_DIFFBUS  DIFF BUS_0.22UF 6.3V 20% X6S  pkg C0201  page 64 : \1\ = P5E_CPU0_P3_TX_C_DP<0> ; \2\ = P5E_CPU0_P3_TX_DP<0>

(kicad_pcb
	(version 20260206)
	(generator "pcbnew")
	(generator_version "10.0")
	(general
		(thickness 1.6)
		(legacy_teardrops no)
	)
	(paper "A4")
	(title_block
		(title "04192023_DAF0TMB3IC0_F0TG_MB_C_brd_V02_OCP.brd")
		(comment 1 "Grand Teton / footprints 3594-3596 of 8354")
	)
	(layers
		(0 "F.Cu" signal "TOP")
		(4 "In1.Cu" signal "GND")
		(6 "In2.Cu" signal "IN1")
		(8 "In3.Cu" signal "GND1")
		(10 "In4.Cu" signal "IN2")
		(12 "In5.Cu" signal "GND2")
		(14 "In6.Cu" signal "IN3")
		(16 "In7.Cu" signal "GND3")
		(18 "In8.Cu" signal "VCC")
		(20 "In9.Cu" signal "VCC1")
		(22 "In10.Cu" signal "GND4")
		(24 "In11.Cu" signal "IN4")
		(26 "In12.Cu" signal "GND5")
		(28 "In13.Cu" signal "IN5")
		(30 "In14.Cu" signal "GND6")
		(32 "In15.Cu" signal "IN6")
		(34 "In16.Cu" signal "GND7")
		(2 "B.Cu" signal "BOTTOM")
		(9 "F.Adhes" user "F.Adhesive")
		(11 "B.Adhes" user "B.Adhesive")
		(13 "F.Paste" user "Package Geometry/Pastemask Top")
		(15 "B.Paste" user "Package Geometry/Pastemask Bottom")
		(5 "F.SilkS" user "Ref Des/Silkscreen Top")
		(7 "B.SilkS" user "Ref Des/Silkscreen Bottom")
		(1 "F.Mask" user "Board Geometry/Soldermask Top")
		(3 "B.Mask" user "Board Geometry/Soldermask Bottom")
		(17 "Dwgs.User" user "User.Drawings")
		(19 "Cmts.User" user "User.Comments")
		(21 "Eco1.User" user "User.Eco1")
		(23 "Eco2.User" user "User.Eco2")
		(25 "Edge.Cuts" user "Board Geometry/Outline")
		(27 "Margin" user)
		(31 "F.CrtYd" user "Package Geometry/Place Bound Top")
		(29 "B.CrtYd" user "Package Geometry/Place Bound Bottom")
		(35 "F.Fab" user "Ref Des/Assembly Top")
		(33 "B.Fab" user "Ref Des/Assembly Bottom")
	)
	(footprint ""
		(layer "F.Cu")
		(at 102.87 -426.466 90)
		(property "Reference" "R3489"
			(at 0 0 90)
			(layer "F.SilkS")
			(hide yes)
			(effects
				(font
					(size 1.27 1.27)
				)
			)
		)
		(property "Value" ""
			(at 0 0 90)
			(layer "F.Fab")
			(effects
				(font
					(size 1.27 1.27)
				)
			)
		)
		(duplicate_pad_numbers_are_jumpers no)
		(fp_line
			(start 0.7874 -0.4064)
			(end 0.7874 0.4064)
			(stroke
				(width 0.1524)
				(type default)
			)
			(layer "F.SilkS")
		)
		(fp_line
			(start -0.7874 -0.4064)
			(end 0.7874 -0.4064)
			(stroke
				(width 0.1524)
				(type default)
			)
			(layer "F.SilkS")
		)
		(fp_line
			(start 0.7874 0.4064)
			(end -0.7874 0.4064)
			(stroke
				(width 0.1524)
				(type default)
			)
			(layer "F.SilkS")
		)
		(fp_line
			(start -0.7874 0.4064)
			(end -0.7874 -0.4064)
			(stroke
				(width 0.1524)
				(type default)
			)
			(layer "F.SilkS")
		)
		(fp_line
			(start -0.12065 -0.305054)
			(end -0.12065 -0.2794)
			(stroke
				(width 0.1)
				(type default)
			)
			(layer "F.Fab")
		)
		(fp_line
			(start -0.67945 -0.305054)
			(end -0.12065 -0.305054)
			(stroke
				(width 0.1)
				(type default)
			)
			(layer "F.Fab")
		)
		(fp_line
			(start 0.67945 -0.3048)
			(end 0.67945 0.3048)
			(stroke
				(width 0.1)
				(type default)
			)
			(layer "F.Fab")
		)
		(fp_line
			(start 0.12065 -0.3048)
			(end 0.67945 -0.3048)
			(stroke
				(width 0.1)
				(type default)
			)
			(layer "F.Fab")
		)
		(fp_line
			(start 0.12065 -0.2794)
			(end 0.12065 -0.3048)
			(stroke
				(width 0.1)
				(type default)
			)
			(layer "F.Fab")
		)
		(fp_line
			(start -0.12065 -0.2794)
			(end 0.12065 -0.2794)
			(stroke
				(width 0.1)
				(type default)
			)
			(layer "F.Fab")
		)
		(fp_line
			(start 0.120396 0.2794)
			(end -0.12065 0.2794)
			(stroke
				(width 0.1)
				(type default)
			)
			(layer "F.Fab")
		)
		(fp_line
			(start -0.12065 0.2794)
			(end -0.12065 0.3048)
			(stroke
				(width 0.1)
				(type default)
			)
			(layer "F.Fab")
		)
		(fp_line
			(start 0.67945 0.3048)
			(end 0.120396 0.3048)
			(stroke
				(width 0.1)
				(type default)
			)
			(layer "F.Fab")
		)
		(fp_line
			(start 0.120396 0.3048)
			(end 0.120396 0.2794)
			(stroke
				(width 0.1)
				(type default)
			)
			(layer "F.Fab")
		)
		(fp_line
			(start -0.12065 0.3048)
			(end -0.67945 0.3048)
			(stroke
				(width 0.1)
				(type default)
			)
			(layer "F.Fab")
		)
		(fp_line
			(start -0.67945 0.3048)
			(end -0.67945 -0.305054)
			(stroke
				(width 0.1)
				(type default)
			)
			(layer "F.Fab")
		)
		(pad "1" smd circle
			(at -0.40005 0 90)
			(size 0 0)
			(layers "F.Cu" "F.Mask" "F.Paste")
			(net "GPU_FPGA_EROT_RST_N")
		)
		(pad "2" smd circle
			(at 0.40005 0 90)
			(size 0 0)
			(layers "F.Cu" "F.Mask" "F.Paste")
			(net "GND")
		)
	)
	(footprint ""
		(layer "F.Cu")
		(at 366.06734 -390.77646 180)
		(property "Reference" "C901"
			(at 0 0 180)
			(layer "F.SilkS")
			(hide yes)
			(effects
				(font
					(size 1.27 1.27)
				)
			)
		)
		(property "Value" ""
			(at 0 0 180)
			(layer "F.Fab")
			(effects
				(font
					(size 1.27 1.27)
				)
			)
		)
		(duplicate_pad_numbers_are_jumpers no)
		(fp_line
			(start 0.299974 0.150114)
			(end -0.299974 0.150114)
			(stroke
				(width 0.1)
				(type default)
			)
			(layer "F.Fab")
		)
		(fp_line
			(start 0.299974 -0.150114)
			(end 0.299974 0.150114)
			(stroke
				(width 0.1)
				(type default)
			)
			(layer "F.Fab")
		)
		(fp_line
			(start -0.299974 0.150114)
			(end -0.299974 -0.150114)
			(stroke
				(width 0.1)
				(type default)
			)
			(layer "F.Fab")
		)
		(fp_line
			(start -0.299974 -0.150114)
			(end 0.299974 -0.150114)
			(stroke
				(width 0.1)
				(type default)
			)
			(layer "F.Fab")
		)
		(pad "1" smd rect
			(at -0.2667 0 180)
			(size 0.3048 0.381)
			(layers "F.Cu" "F.Mask" "F.Paste")
			(net "P5E_CPU0_P3_TX_C_DP<0>")
		)
		(pad "2" smd rect
			(at 0.2667 0 180)
			(size 0.3048 0.381)
			(layers "F.Cu" "F.Mask" "F.Paste")
			(net "P5E_CPU0_P3_TX_DP<0>")
		)
	)
	(footprint ""
		(layer "F.Cu")
		(at 52.23891 -351.932748)
		(property "Reference" "PR275"
			(at 0 0 0)
			(layer "F.SilkS")
			(hide yes)
			(effects
				(font
					(size 1.27 1.27)
				)
			)
		)
		(property "Value" ""
			(at 0 0 0)
			(layer "F.Fab")
			(effects
				(font
					(size 1.27 1.27)
				)
			)
		)
		(duplicate_pad_numbers_are_jumpers no)
		(fp_line
			(start -0.7874 -0.4064)
			(end 0.7874 -0.4064)
			(stroke
				(width 0.1524)
				(type default)
			)
			(layer "F.SilkS")
		)
		(fp_line
			(start -0.7874 0.4064)
			(end -0.7874 -0.4064)
			(stroke
				(width 0.1524)
				(type default)
			)
			(layer "F.SilkS")
		)
		(fp_line
			(start 0.7874 -0.4064)
			(end 0.7874 0.4064)
			(stroke
				(width 0.1524)
				(type default)
			)
			(layer "F.SilkS")
		)
		(fp_line
			(start 0.7874 0.4064)
			(end -0.7874 0.4064)
			(stroke
				(width 0.1524)
				(type default)
			)
			(layer "F.SilkS")
		)
		(fp_line
			(start -0.67945 -0.305054)
			(end -0.12065 -0.305054)
			(stroke
				(width 0.1)
				(type default)
			)
			(layer "F.Fab")
		)
		(fp_line
			(start -0.67945 0.3048)
			(end -0.67945 -0.305054)
			(stroke
				(width 0.1)
				(type default)
			)
			(layer "F.Fab")
		)
		(fp_line
			(start -0.12065 -0.305054)
			(end -0.12065 -0.2794)
			(stroke
				(width 0.1)
				(type default)
			)
			(layer "F.Fab")
		)
		(fp_line
			(start -0.12065 -0.2794)
			(end 0.12065 -0.2794)
			(stroke
				(width 0.1)
				(type default)
			)
			(layer "F.Fab")
		)
		(fp_line
			(start -0.12065 0.2794)
			(end -0.12065 0.3048)
			(stroke
				(width 0.1)
				(type default)
			)
			(layer "F.Fab")
		)
		(fp_line
			(start -0.12065 0.3048)
			(end -0.67945 0.3048)
			(stroke
				(width 0.1)
				(type default)
			)
			(layer "F.Fab")
		)
		(fp_line
			(start 0.120396 0.2794)
			(end -0.12065 0.2794)
			(stroke
				(width 0.1)
				(type default)
			)
			(layer "F.Fab")
		)
		(fp_line
			(start 0.120396 0.3048)
			(end 0.120396 0.2794)
			(stroke
				(width 0.1)
				(type default)
			)
			(layer "F.Fab")
		)
		(fp_line
			(start 0.12065 -0.3048)
			(end 0.67945 -0.3048)
			(stroke
				(width 0.1)
				(type default)
			)
			(layer "F.Fab")
		)
		(fp_line
			(start 0.12065 -0.2794)
			(end 0.12065 -0.3048)
			(stroke
				(width 0.1)
				(type default)
			)
			(layer "F.Fab")
		)
		(fp_line
			(start 0.67945 -0.3048)
			(end 0.67945 0.3048)
			(stroke
				(width 0.1)
				(type default)
			)
			(layer "F.Fab")
		)
		(fp_line
			(start 0.67945 0.3048)
			(end 0.120396 0.3048)
			(stroke
				(width 0.1)
				(type default)
			)
			(layer "F.Fab")
		)
		(pad "1" smd circle
			(at -0.40005 0)
			(size 0 0)
			(layers "F.Cu" "F.Mask" "F.Paste")
			(net "PVDDIO_P1_LSET1")
		)
		(pad "2" smd circle
			(at 0.40005 0)
			(size 0 0)
			(layers "F.Cu" "F.Mask" "F.Paste")
			(net "GND")
		)
	)
)
